(kicad_pcb
	(version 20260206)
	(generator "pcbnew")
	(generator_version "10.0")
	(general
		(thickness 1.6)
		(legacy_teardrops no)
	)
	(paper "A4")
	(title_block
		(title "04192023_DAF0TMB3IC0_F0TG_MB_C_brd_V02_OCP.brd")
		(comment 1 "Grand Teton / footprints 3714-3720 of 8354")
	)
	(layers
		(0 "F.Cu" signal "TOP")
		(4 "In1.Cu" signal "GND")
		(6 "In2.Cu" signal "IN1")
		(8 "In3.Cu" signal "GND1")
		(10 "In4.Cu" signal "IN2")
		(12 "In5.Cu" signal "GND2")
		(14 "In6.Cu" signal "IN3")
		(16 "In7.Cu" signal "GND3")
		(18 "In8.Cu" signal "VCC")
		(20 "In9.Cu" signal "VCC1")
		(22 "In10.Cu" signal "GND4")
		(24 "In11.Cu" signal "IN4")
		(26 "In12.Cu" signal "GND5")
		(28 "In13.Cu" signal "IN5")
		(30 "In14.Cu" signal "GND6")
		(32 "In15.Cu" signal "IN6")
		(34 "In16.Cu" signal "GND7")
		(2 "B.Cu" signal "BOTTOM")
		(9 "F.Adhes" user "F.Adhesive")
		(11 "B.Adhes" user "B.Adhesive")
		(13 "F.Paste" user "Package Geometry/Pastemask Top")
		(15 "B.Paste" user "Package Geometry/Pastemask Bottom")
		(5 "F.SilkS" user "Ref Des/Silkscreen Top")
		(7 "B.SilkS" user "Ref Des/Silkscreen Bottom")
		(1 "F.Mask" user "Board Geometry/Soldermask Top")
		(3 "B.Mask" user "Board Geometry/Soldermask Bottom")
		(17 "Dwgs.User" user "User.Drawings")
		(19 "Cmts.User" user "User.Comments")
		(21 "Eco1.User" user "User.Eco1")
		(23 "Eco2.User" user "User.Eco2")
		(25 "Edge.Cuts" user "Board Geometry/Outline")
		(27 "Margin" user)
		(31 "F.CrtYd" user "Package Geometry/Place Bound Top")
		(29 "B.CrtYd" user "Package Geometry/Place Bound Bottom")
		(35 "F.Fab" user "Ref Des/Assembly Top")
		(33 "B.Fab" user "Ref Des/Assembly Bottom")
	)
	(footprint ""
		(layer "F.Cu")
		(at 215.4301 -401.988782 180)
		(property "Reference" "PR3990"
			(at 0 0 180)
			(layer "F.SilkS")
			(hide yes)
			(effects
				(font
					(size 1.27 1.27)
				)
			)
		)
		(property "Value" ""
			(at 0 0 180)
			(layer "F.Fab")
			(effects
				(font
					(size 1.27 1.27)
				)
			)
		)
		(duplicate_pad_numbers_are_jumpers no)
		(fp_line
			(start 0.7874 0.4064)
			(end -0.7874 0.4064)
			(stroke
				(width 0.1524)
				(type default)
			)
			(layer "F.SilkS")
		)
		(fp_line
			(start 0.7874 -0.4064)
			(end 0.7874 0.4064)
			(stroke
				(width 0.1524)
				(type default)
			)
			(layer "F.SilkS")
		)
		(fp_line
			(start -0.7874 0.4064)
			(end -0.7874 -0.4064)
			(stroke
				(width 0.1524)
				(type default)
			)
			(layer "F.SilkS")
		)
		(fp_line
			(start -0.7874 -0.4064)
			(end 0.7874 -0.4064)
			(stroke
				(width 0.1524)
				(type default)
			)
			(layer "F.SilkS")
		)
		(fp_line
			(start 0.67945 0.3048)
			(end 0.120396 0.3048)
			(stroke
				(width 0.1)
				(type default)
			)
			(layer "F.Fab")
		)
		(fp_line
			(start 0.67945 -0.3048)
			(end 0.67945 0.3048)
			(stroke
				(width 0.1)
				(type default)
			)
			(layer "F.Fab")
		)
		(fp_line
			(start 0.12065 -0.2794)
			(end 0.12065 -0.3048)
			(stroke
				(width 0.1)
				(type default)
			)
			(layer "F.Fab")
		)
		(fp_line
			(start 0.12065 -0.3048)
			(end 0.67945 -0.3048)
			(stroke
				(width 0.1)
				(type default)
			)
			(layer "F.Fab")
		)
		(fp_line
			(start 0.120396 0.3048)
			(end 0.120396 0.2794)
			(stroke
				(width 0.1)
				(type default)
			)
			(layer "F.Fab")
		)
		(fp_line
			(start 0.120396 0.2794)
			(end -0.12065 0.2794)
			(stroke
				(width 0.1)
				(type default)
			)
			(layer "F.Fab")
		)
		(fp_line
			(start -0.12065 0.3048)
			(end -0.67945 0.3048)
			(stroke
				(width 0.1)
				(type default)
			)
			(layer "F.Fab")
		)
		(fp_line
			(start -0.12065 0.2794)
			(end -0.12065 0.3048)
			(stroke
				(width 0.1)
				(type default)
			)
			(layer "F.Fab")
		)
		(fp_line
			(start -0.12065 -0.2794)
			(end 0.12065 -0.2794)
			(stroke
				(width 0.1)
				(type default)
			)
			(layer "F.Fab")
		)
		(fp_line
			(start -0.12065 -0.305054)
			(end -0.12065 -0.2794)
			(stroke
				(width 0.1)
				(type default)
			)
			(layer "F.Fab")
		)
		(fp_line
			(start -0.67945 0.3048)
			(end -0.67945 -0.305054)
			(stroke
				(width 0.1)
				(type default)
			)
			(layer "F.Fab")
		)
		(fp_line
			(start -0.67945 -0.305054)
			(end -0.12065 -0.305054)
			(stroke
				(width 0.1)
				(type default)
			)
			(layer "F.Fab")
		)
		(pad "1" smd circle
			(at -0.40005 0 180)
			(size 0 0)
			(layers "F.Cu" "F.Mask" "F.Paste")
			(net "HSC_IMON")
		)
		(pad "2" smd circle
			(at 0.40005 0 180)
			(size 0 0)
			(layers "F.Cu" "F.Mask" "F.Paste")
			(net "AGND_HSC")
		)
	)
	(footprint ""
		(layer "F.Cu")
		(at 329.592178 -42.176954 180)
		(property "Reference" "R2908"
			(at 0 0 180)
			(layer "F.SilkS")
			(hide yes)
			(effects
				(font
					(size 1.27 1.27)
				)
			)
		)
		(property "Value" ""
			(at 0 0 180)
			(layer "F.Fab")
			(effects
				(font
					(size 1.27 1.27)
				)
			)
		)
		(duplicate_pad_numbers_are_jumpers no)
		(fp_line
			(start 0.7874 0.4064)
			(end -0.7874 0.4064)
			(stroke
				(width 0.1524)
				(type default)
			)
			(layer "F.SilkS")
		)
		(fp_line
			(start 0.7874 -0.4064)
			(end 0.7874 0.4064)
			(stroke
				(width 0.1524)
				(type default)
			)
			(layer "F.SilkS")
		)
		(fp_line
			(start -0.7874 0.4064)
			(end -0.7874 -0.4064)
			(stroke
				(width 0.1524)
				(type default)
			)
			(layer "F.SilkS")
		)
		(fp_line
			(start -0.7874 -0.4064)
			(end 0.7874 -0.4064)
			(stroke
				(width 0.1524)
				(type default)
			)
			(layer "F.SilkS")
		)
		(fp_line
			(start 0.67945 0.3048)
			(end 0.120396 0.3048)
			(stroke
				(width 0.1)
				(type default)
			)
			(layer "F.Fab")
		)
		(fp_line
			(start 0.67945 -0.3048)
			(end 0.67945 0.3048)
			(stroke
				(width 0.1)
				(type default)
			)
			(layer "F.Fab")
		)
		(fp_line
			(start 0.12065 -0.2794)
			(end 0.12065 -0.3048)
			(stroke
				(width 0.1)
				(type default)
			)
			(layer "F.Fab")
		)
		(fp_line
			(start 0.12065 -0.3048)
			(end 0.67945 -0.3048)
			(stroke
				(width 0.1)
				(type default)
			)
			(layer "F.Fab")
		)
		(fp_line
			(start 0.120396 0.3048)
			(end 0.120396 0.2794)
			(stroke
				(width 0.1)
				(type default)
			)
			(layer "F.Fab")
		)
		(fp_line
			(start 0.120396 0.2794)
			(end -0.12065 0.2794)
			(stroke
				(width 0.1)
				(type default)
			)
			(layer "F.Fab")
		)
		(fp_line
			(start -0.12065 0.3048)
			(end -0.67945 0.3048)
			(stroke
				(width 0.1)
				(type default)
			)
			(layer "F.Fab")
		)
		(fp_line
			(start -0.12065 0.2794)
			(end -0.12065 0.3048)
			(stroke
				(width 0.1)
				(type default)
			)
			(layer "F.Fab")
		)
		(fp_line
			(start -0.12065 -0.2794)
			(end 0.12065 -0.2794)
			(stroke
				(width 0.1)
				(type default)
			)
			(layer "F.Fab")
		)
		(fp_line
			(start -0.12065 -0.305054)
			(end -0.12065 -0.2794)
			(stroke
				(width 0.1)
				(type default)
			)
			(layer "F.Fab")
		)
		(fp_line
			(start -0.67945 0.3048)
			(end -0.67945 -0.305054)
			(stroke
				(width 0.1)
				(type default)
			)
			(layer "F.Fab")
		)
		(fp_line
			(start -0.67945 -0.305054)
			(end -0.12065 -0.305054)
			(stroke
				(width 0.1)
				(type default)
			)
			(layer "F.Fab")
		)
		(pad "1" smd circle
			(at -0.40005 0 180)
			(size 0 0)
			(layers "F.Cu" "F.Mask" "F.Paste")
			(net "P3V3")
		)
		(pad "2" smd circle
			(at 0.40005 0 180)
			(size 0 0)
			(layers "F.Cu" "F.Mask" "F.Paste")
			(net "P3V3_ADC")
		)
	)
	(footprint ""
		(layer "F.Cu")
		(at 385.214114 -178.359562 180)
		(property "Reference" "PC551_4"
			(at 0 0 180)
			(layer "F.SilkS")
			(hide yes)
			(effects
				(font
					(size 1.27 1.27)
				)
			)
		)
		(property "Value" ""
			(at 0 0 180)
			(layer "F.Fab")
			(effects
				(font
					(size 1.27 1.27)
				)
			)
		)
		(duplicate_pad_numbers_are_jumpers no)
		(fp_line
			(start 0.7874 0.4064)
			(end -0.7874 0.4064)
			(stroke
				(width 0.1524)
				(type default)
			)
			(layer "F.SilkS")
		)
		(fp_line
			(start 0.7874 -0.4064)
			(end 0.7874 0.4064)
			(stroke
				(width 0.1524)
				(type default)
			)
			(layer "F.SilkS")
		)
		(fp_line
			(start -0.7874 0.4064)
			(end -0.7874 -0.4064)
			(stroke
				(width 0.1524)
				(type default)
			)
			(layer "F.SilkS")
		)
		(fp_line
			(start -0.7874 -0.4064)
			(end 0.7874 -0.4064)
			(stroke
				(width 0.1524)
				(type default)
			)
			(layer "F.SilkS")
		)
		(fp_line
			(start 0.67945 0.3048)
			(end 0.120396 0.3048)
			(stroke
				(width 0.1)
				(type default)
			)
			(layer "F.Fab")
		)
		(fp_line
			(start 0.67945 -0.3048)
			(end 0.67945 0.3048)
			(stroke
				(width 0.1)
				(type default)
			)
			(layer "F.Fab")
		)
		(fp_line
			(start 0.12065 -0.2794)
			(end 0.12065 -0.3048)
			(stroke
				(width 0.1)
				(type default)
			)
			(layer "F.Fab")
		)
		(fp_line
			(start 0.12065 -0.3048)
			(end 0.67945 -0.3048)
			(stroke
				(width 0.1)
				(type default)
			)
			(layer "F.Fab")
		)
		(fp_line
			(start 0.120396 0.3048)
			(end 0.120396 0.2794)
			(stroke
				(width 0.1)
				(type default)
			)
			(layer "F.Fab")
		)
		(fp_line
			(start 0.120396 0.2794)
			(end -0.12065 0.2794)
			(stroke
				(width 0.1)
				(type default)
			)
			(layer "F.Fab")
		)
		(fp_line
			(start -0.12065 0.3048)
			(end -0.67945 0.3048)
			(stroke
				(width 0.1)
				(type default)
			)
			(layer "F.Fab")
		)
		(fp_line
			(start -0.12065 0.2794)
			(end -0.12065 0.3048)
			(stroke
				(width 0.1)
				(type default)
			)
			(layer "F.Fab")
		)
		(fp_line
			(start -0.12065 -0.2794)
			(end 0.12065 -0.2794)
			(stroke
				(width 0.1)
				(type default)
			)
			(layer "F.Fab")
		)
		(fp_line
			(start -0.12065 -0.305054)
			(end -0.12065 -0.2794)
			(stroke
				(width 0.1)
				(type default)
			)
			(layer "F.Fab")
		)
		(fp_line
			(start -0.67945 0.3048)
			(end -0.67945 -0.305054)
			(stroke
				(width 0.1)
				(type default)
			)
			(layer "F.Fab")
		)
		(fp_line
			(start -0.67945 -0.305054)
			(end -0.12065 -0.305054)
			(stroke
				(width 0.1)
				(type default)
			)
			(layer "F.Fab")
		)
		(pad "1" smd circle
			(at -0.40005 0 180)
			(size 0 0)
			(layers "F.Cu" "F.Mask" "F.Paste")
			(net "SW_P12V_AUX_PVDDCR_CPU0_P0_FLT")
		)
		(pad "2" smd circle
			(at 0.40005 0 180)
			(size 0 0)
			(layers "F.Cu" "F.Mask" "F.Paste")
			(net "GND")
		)
	)
	(footprint ""
		(layer "F.Cu")
		(at 360.172 -401.4216)
		(property "Reference" "R1392"
			(at 0 0 0)
			(layer "F.SilkS")
			(hide yes)
			(effects
				(font
					(size 1.27 1.27)
				)
			)
		)
		(property "Value" ""
			(at 0 0 0)
			(layer "F.Fab")
			(effects
				(font
					(size 1.27 1.27)
				)
			)
		)
		(duplicate_pad_numbers_are_jumpers no)
		(fp_line
			(start -0.32512 -0.175006)
			(end 0.32512 -0.175006)
			(stroke
				(width 0.1)
				(type default)
			)
			(layer "F.Fab")
		)
		(fp_line
			(start -0.32512 0.175006)
			(end -0.32512 -0.175006)
			(stroke
				(width 0.1)
				(type default)
			)
			(layer "F.Fab")
		)
		(fp_line
			(start 0.32512 -0.175006)
			(end 0.32512 0.175006)
			(stroke
				(width 0.1)
				(type default)
			)
			(layer "F.Fab")
		)
		(fp_line
			(start 0.32512 0.175006)
			(end -0.32512 0.175006)
			(stroke
				(width 0.1)
				(type default)
			)
			(layer "F.Fab")
		)
		(pad "1" smd rect
			(at -0.2667 0)
			(size 0.3048 0.381)
			(layers "F.Cu" "F.Mask" "F.Paste")
			(net "JTAG_TCK_RT_CPU0_P1")
		)
		(pad "2" smd rect
			(at 0.2667 0 180)
			(size 0.3048 0.381)
			(layers "F.Cu" "F.Mask" "F.Paste")
			(net "GND")
		)
	)
	(footprint ""
		(layer "F.Cu")
		(at 257.242056 -117.89537 180)
		(property "Reference" "R3718"
			(at 0 0 180)
			(layer "F.SilkS")
			(hide yes)
			(effects
				(font
					(size 1.27 1.27)
				)
			)
		)
		(property "Value" ""
			(at 0 0 180)
			(layer "F.Fab")
			(effects
				(font
					(size 1.27 1.27)
				)
			)
		)
		(duplicate_pad_numbers_are_jumpers no)
		(fp_line
			(start 0.7874 0.4064)
			(end -0.7874 0.4064)
			(stroke
				(width 0.1524)
				(type default)
			)
			(layer "F.SilkS")
		)
		(fp_line
			(start 0.7874 -0.4064)
			(end 0.7874 0.4064)
			(stroke
				(width 0.1524)
				(type default)
			)
			(layer "F.SilkS")
		)
		(fp_line
			(start -0.7874 0.4064)
			(end -0.7874 -0.4064)
			(stroke
				(width 0.1524)
				(type default)
			)
			(layer "F.SilkS")
		)
		(fp_line
			(start -0.7874 -0.4064)
			(end 0.7874 -0.4064)
			(stroke
				(width 0.1524)
				(type default)
			)
			(layer "F.SilkS")
		)
		(fp_line
			(start 0.67945 0.3048)
			(end 0.120396 0.3048)
			(stroke
				(width 0.1)
				(type default)
			)
			(layer "F.Fab")
		)
		(fp_line
			(start 0.67945 -0.3048)
			(end 0.67945 0.3048)
			(stroke
				(width 0.1)
				(type default)
			)
			(layer "F.Fab")
		)
		(fp_line
			(start 0.12065 -0.2794)
			(end 0.12065 -0.3048)
			(stroke
				(width 0.1)
				(type default)
			)
			(layer "F.Fab")
		)
		(fp_line
			(start 0.12065 -0.3048)
			(end 0.67945 -0.3048)
			(stroke
				(width 0.1)
				(type default)
			)
			(layer "F.Fab")
		)
		(fp_line
			(start 0.120396 0.3048)
			(end 0.120396 0.2794)
			(stroke
				(width 0.1)
				(type default)
			)
			(layer "F.Fab")
		)
		(fp_line
			(start 0.120396 0.2794)
			(end -0.12065 0.2794)
			(stroke
				(width 0.1)
				(type default)
			)
			(layer "F.Fab")
		)
		(fp_line
			(start -0.12065 0.3048)
			(end -0.67945 0.3048)
			(stroke
				(width 0.1)
				(type default)
			)
			(layer "F.Fab")
		)
		(fp_line
			(start -0.12065 0.2794)
			(end -0.12065 0.3048)
			(stroke
				(width 0.1)
				(type default)
			)
			(layer "F.Fab")
		)
		(fp_line
			(start -0.12065 -0.2794)
			(end 0.12065 -0.2794)
			(stroke
				(width 0.1)
				(type default)
			)
			(layer "F.Fab")
		)
		(fp_line
			(start -0.12065 -0.305054)
			(end -0.12065 -0.2794)
			(stroke
				(width 0.1)
				(type default)
			)
			(layer "F.Fab")
		)
		(fp_line
			(start -0.67945 0.3048)
			(end -0.67945 -0.305054)
			(stroke
				(width 0.1)
				(type default)
			)
			(layer "F.Fab")
		)
		(fp_line
			(start -0.67945 -0.305054)
			(end -0.12065 -0.305054)
			(stroke
				(width 0.1)
				(type default)
			)
			(layer "F.Fab")
		)
		(pad "1" smd circle
			(at -0.40005 0 180)
			(size 0 0)
			(layers "F.Cu" "F.Mask" "F.Paste")
			(net "SMB_LM75_1_3V3AUX_SDA_R")
		)
		(pad "2" smd circle
			(at 0.40005 0 180)
			(size 0 0)
			(layers "F.Cu" "F.Mask" "F.Paste")
			(net "SMB_LM75_1_3V3AUX_SDA")
		)
	)
	(footprint ""
		(layer "F.Cu")
		(at 47.91456 -105.08234)
		(property "Reference" "C1114"
			(at 0 0 0)
			(layer "F.SilkS")
			(hide yes)
			(effects
				(font
					(size 1.27 1.27)
				)
			)
		)
		(property "Value" ""
			(at 0 0 0)
			(layer "F.Fab")
			(effects
				(font
					(size 1.27 1.27)
				)
			)
		)
		(duplicate_pad_numbers_are_jumpers no)
		(fp_line
			(start -1.524 -0.762)
			(end 1.524 -0.762)
			(stroke
				(width 0.1524)
				(type default)
			)
			(layer "F.SilkS")
		)
		(fp_line
			(start -1.524 0.762)
			(end -1.524 -0.762)
			(stroke
				(width 0.1524)
				(type default)
			)
			(layer "F.SilkS")
		)
		(fp_line
			(start 1.524 -0.762)
			(end 1.524 0.762)
			(stroke
				(width 0.1524)
				(type default)
			)
			(layer "F.SilkS")
		)
		(fp_line
			(start 1.524 0.762)
			(end -1.524 0.762)
			(stroke
				(width 0.1524)
				(type default)
			)
			(layer "F.SilkS")
		)
		(fp_line
			(start -1.1049 -0.724916)
			(end -1.1049 0.724916)
			(stroke
				(width 0.1)
				(type default)
			)
			(layer "F.Fab")
		)
		(fp_line
			(start -1.1049 0.724916)
			(end 1.1049 0.724916)
			(stroke
				(width 0.1)
				(type default)
			)
			(layer "F.Fab")
		)
		(fp_line
			(start 1.1049 -0.724916)
			(end -1.1049 -0.724916)
			(stroke
				(width 0.1)
				(type default)
			)
			(layer "F.Fab")
		)
		(fp_line
			(start 1.1049 0.724916)
			(end 1.1049 -0.724916)
			(stroke
				(width 0.1)
				(type default)
			)
			(layer "F.Fab")
		)
		(pad "1" smd rect
			(at -0.889 0 180)
			(size 1.016 1.27)
			(layers "F.Cu" "F.Mask" "F.Paste")
			(net "P3V3_AUX_DSC_S1")
		)
		(pad "2" smd rect
			(at 0.889 0 180)
			(size 1.016 1.27)
			(layers "F.Cu" "F.Mask" "F.Paste")
			(net "GND")
		)
	)
	(footprint ""
		(layer "F.Cu")
		(at 126.804928 -50.169064 180)
		(property "Reference" "R6214"
			(at 0 0 180)
			(layer "F.SilkS")
			(hide yes)
			(effects
				(font
					(size 1.27 1.27)
				)
			)
		)
		(property "Value" ""
			(at 0 0 180)
			(layer "F.Fab")
			(effects
				(font
					(size 1.27 1.27)
				)
			)
		)
		(duplicate_pad_numbers_are_jumpers no)
		(fp_line
			(start 0.7874 0.4064)
			(end -0.7874 0.4064)
			(stroke
				(width 0.1524)
				(type default)
			)
			(layer "F.SilkS")
		)
		(fp_line
			(start 0.7874 -0.4064)
			(end 0.7874 0.4064)
			(stroke
				(width 0.1524)
				(type default)
			)
			(layer "F.SilkS")
		)
		(fp_line
			(start -0.7874 0.4064)
			(end -0.7874 -0.4064)
			(stroke
				(width 0.1524)
				(type default)
			)
			(layer "F.SilkS")
		)
		(fp_line
			(start -0.7874 -0.4064)
			(end 0.7874 -0.4064)
			(stroke
				(width 0.1524)
				(type default)
			)
			(layer "F.SilkS")
		)
		(fp_line
			(start 0.67945 0.3048)
			(end 0.120396 0.3048)
			(stroke
				(width 0.1)
				(type default)
			)
			(layer "F.Fab")
		)
		(fp_line
			(start 0.67945 -0.3048)
			(end 0.67945 0.3048)
			(stroke
				(width 0.1)
				(type default)
			)
			(layer "F.Fab")
		)
		(fp_line
			(start 0.12065 -0.2794)
			(end 0.12065 -0.3048)
			(stroke
				(width 0.1)
				(type default)
			)
			(layer "F.Fab")
		)
		(fp_line
			(start 0.12065 -0.3048)
			(end 0.67945 -0.3048)
			(stroke
				(width 0.1)
				(type default)
			)
			(layer "F.Fab")
		)
		(fp_line
			(start 0.120396 0.3048)
			(end 0.120396 0.2794)
			(stroke
				(width 0.1)
				(type default)
			)
			(layer "F.Fab")
		)
		(fp_line
			(start 0.120396 0.2794)
			(end -0.12065 0.2794)
			(stroke
				(width 0.1)
				(type default)
			)
			(layer "F.Fab")
		)
		(fp_line
			(start -0.12065 0.3048)
			(end -0.67945 0.3048)
			(stroke
				(width 0.1)
				(type default)
			)
			(layer "F.Fab")
		)
		(fp_line
			(start -0.12065 0.2794)
			(end -0.12065 0.3048)
			(stroke
				(width 0.1)
				(type default)
			)
			(layer "F.Fab")
		)
		(fp_line
			(start -0.12065 -0.2794)
			(end 0.12065 -0.2794)
			(stroke
				(width 0.1)
				(type default)
			)
			(layer "F.Fab")
		)
		(fp_line
			(start -0.12065 -0.305054)
			(end -0.12065 -0.2794)
			(stroke
				(width 0.1)
				(type default)
			)
			(layer "F.Fab")
		)
		(fp_line
			(start -0.67945 0.3048)
			(end -0.67945 -0.305054)
			(stroke
				(width 0.1)
				(type default)
			)
			(layer "F.Fab")
		)
		(fp_line
			(start -0.67945 -0.305054)
			(end -0.12065 -0.305054)
			(stroke
				(width 0.1)
				(type default)
			)
			(layer "F.Fab")
		)
		(pad "1" smd circle
			(at -0.40005 0 180)
			(size 0 0)
			(layers "F.Cu" "F.Mask" "F.Paste")
			(net "USB_CPU0_HUB1_MODE_SEL1")
		)
		(pad "2" smd circle
			(at 0.40005 0 180)
			(size 0 0)
			(layers "F.Cu" "F.Mask" "F.Paste")
			(net "GND")
		)
	)
)
